#ISCELL
  pure_quanta quanta_title_block_c *
  *
#CELL
  pure_quanta q_cap *
  page72_i1
#CELL
  pure_quanta q_cap *
  page72_i10
#CELL
  pure_quanta q_cap *
  page72_i100
#CELL
  pure_quanta q_cap *
  page72_i101
#CELL
  pure_quanta q_cap *
  page72_i102
#CELL
  pure_quanta q_cap *
  page72_i103
#CELL
  pure_quanta q_cap *
  page72_i104
#CELL
  pure_quanta q_cap *
  page72_i105
#CELL
  pure_quanta q_cap *
  page72_i106
#CELL
  pure_quanta q_cap *
  page72_i107
#ISCELL
  pure_quanta_power universal_gnd *
  page72_i108
#CELL
  pure_quanta q_cap *
  page72_i109
#CELL
  pure_quanta q_cap *
  page72_i11
#CELL
  pure_quanta q_cap *
  page72_i110
#CELL
  pure_quanta q_cap *
  page72_i12
#CELL
  pure_quanta q_cap *
  page72_i13
#CELL
  pure_quanta q_cap *
  page72_i14
#CELL
  pure_quanta q_cap *
  page72_i15
#ISCELL
  pure_quanta_power universal_power *
  page72_i16
#CELL
  pure_quanta q_cap *
  page72_i17
#ISCELL
  pure_quanta_power universal_power *
  page72_i18
#CELL
  pure_quanta q_cap *
  page72_i19
#ISCELL
  pure_quanta_power universal_power *
  page72_i2
#CELL
  pure_quanta q_cap *
  page72_i20
#CELL
  pure_quanta q_cap *
  page72_i21
#ISCELL
  pure_quanta_power universal_gnd *
  page72_i22
#CELL
  pure_quanta q_cap *
  page72_i23
#CELL
  pure_quanta q_cap *
  page72_i24
#CELL
  pure_quanta q_cap *
  page72_i25
#CELL
  pure_quanta q_cap *
  page72_i26
#CELL
  pure_quanta q_cap *
  page72_i27
#CELL
  pure_quanta q_cap *
  page72_i28
#CELL
  pure_quanta q_cap *
  page72_i29
#CELL
  pure_quanta q_cap *
  page72_i3
#CELL
  pure_quanta q_cap *
  page72_i30
#CELL
  pure_quanta q_cap *
  page72_i31
#CELL
  pure_quanta q_cap *
  page72_i32
#CELL
  pure_quanta q_cap *
  page72_i33
#CELL
  pure_quanta q_cap *
  page72_i34
#CELL
  pure_quanta q_cap *
  page72_i35
#CELL
  pure_quanta q_cap *
  page72_i36
#CELL
  pure_quanta q_cap *
  page72_i37
#CELL
  pure_quanta q_cap *
  page72_i38
#ISCELL
  pure_quanta_power universal_power *
  page72_i39
#CELL
  pure_quanta q_cap *
  page72_i4
#CELL
  pure_quanta q_cap *
  page72_i40
#CELL
  pure_quanta q_cap *
  page72_i41
#CELL
  pure_quanta q_cap *
  page72_i42
#ISCELL
  pure_quanta_power universal_gnd *
  page72_i43
#CELL
  pure_quanta q_cap *
  page72_i44
#ISCELL
  pure_quanta_power universal_gnd *
  page72_i45
#CELL
  pure_quanta q_cap *
  page72_i46
#CELL
  pure_quanta q_cap *
  page72_i47
#CELL
  pure_quanta q_cap *
  page72_i48
#ISCELL
  pure_quanta_power universal_gnd *
  page72_i49
#CELL
  pure_quanta q_cap *
  page72_i5
#CELL
  pure_quanta q_cap *
  page72_i50
#CELL
  pure_quanta q_cap *
  page72_i51
#ISCELL
  pure_quanta_power universal_power *
  page72_i52
#CELL
  pure_quanta q_cap *
  page72_i53
#ISCELL
  pure_quanta_power universal_power *
  page72_i54
#CELL
  pure_quanta q_cap *
  page72_i55
#CELL
  pure_quanta q_cap *
  page72_i56
#CELL
  pure_quanta q_cap *
  page72_i57
#CELL
  pure_quanta q_cap *
  page72_i58
#CELL
  pure_quanta q_cap *
  page72_i59
#ISCELL
  pure_quanta_power universal_power *
  page72_i6
#CELL
  pure_quanta q_cap *
  page72_i60
#CELL
  pure_quanta q_cap *
  page72_i61
#CELL
  pure_quanta q_cap *
  page72_i62
#CELL
  pure_quanta q_cap *
  page72_i63
#CELL
  pure_quanta q_cap *
  page72_i64
#ISCELL
  pure_quanta_power universal_gnd *
  page72_i65
#CELL
  pure_quanta q_cap *
  page72_i66
#ISCELL
  pure_quanta_power universal_power *
  page72_i67
#CELL
  pure_quanta q_cap *
  page72_i68
#ISCELL
  pure_quanta_power universal_power *
  page72_i69
#CELL
  pure_quanta q_cap *
  page72_i7
#CELL
  pure_quanta q_cap *
  page72_i70
#CELL
  pure_quanta q_cap *
  page72_i71
#CELL
  pure_quanta q_cap *
  page72_i72
#ISCELL
  pure_quanta_power universal_gnd *
  page72_i73
#CELL
  pure_quanta q_cap *
  page72_i74
#CELL
  pure_quanta q_cap *
  page72_i75
#CELL
  pure_quanta q_cap *
  page72_i76
#CELL
  pure_quanta q_cap *
  page72_i77
#CELL
  pure_quanta q_cap *
  page72_i78
#CELL
  pure_quanta q_cap *
  page72_i79
#ISCELL
  pure_quanta_power universal_power *
  page72_i8
#CELL
  pure_quanta q_cap *
  page72_i80
#CELL
  pure_quanta q_cap *
  page72_i81
#CELL
  pure_quanta q_cap *
  page72_i82
#CELL
  pure_quanta q_cap *
  page72_i83
#CELL
  pure_quanta q_cap *
  page72_i84
#CELL
  pure_quanta q_cap *
  page72_i85
#CELL
  pure_quanta q_cap *
  page72_i86
#CELL
  pure_quanta q_cap *
  page72_i87
#CELL
  pure_quanta q_cap *
  page72_i88
#CELL
  pure_quanta q_cap *
  page72_i89
#CELL
  pure_quanta q_cap *
  page72_i9
#CELL
  pure_quanta q_cap *
  page72_i90
#CELL
  pure_quanta q_cap *
  page72_i91
#CELL
  pure_quanta q_cap *
  page72_i92
#CELL
  pure_quanta q_cap *
  page72_i93
#CELL
  pure_quanta q_cap *
  page72_i94
#ISCELL
  pure_quanta_power universal_gnd *
  page72_i95
#CELL
  pure_quanta q_cap *
  page72_i96
#ISCELL
  pure_quanta_power universal_gnd *
  page72_i97
#CELL
  pure_quanta q_cap *
  page72_i98
#ISCELL
  pure_quanta_power universal_gnd *
  page72_i99
